(kicad_pcb
	(version 20260206)
	(generator "pcbnew")
	(generator_version "10.0")
	(general
		(thickness 1.6)
		(legacy_teardrops no)
	)
	(paper "A4")
	(title_block
		(title "Wiwynn_Tioga_Pass_MB.brd")
		(comment 1 "Tioga Pass / footprints 2057-2063 of 4770")
	)
	(layers
		(0 "F.Cu" signal "TOP")
		(4 "In1.Cu" signal "L2GND")
		(6 "In2.Cu" signal "L3")
		(8 "In3.Cu" signal "L4GND")
		(10 "In4.Cu" signal "L5")
		(12 "In5.Cu" signal "L6GND")
		(14 "In6.Cu" signal "L7VCC")
		(16 "In7.Cu" signal "L8VCC")
		(18 "In8.Cu" signal "L9GND")
		(20 "In9.Cu" signal "L10")
		(22 "In10.Cu" signal "L11GND")
		(24 "In11.Cu" signal "L12")
		(26 "In12.Cu" signal "L13GND")
		(2 "B.Cu" signal "BOTTOM")
		(9 "F.Adhes" user "F.Adhesive")
		(11 "B.Adhes" user "B.Adhesive")
		(13 "F.Paste" user "Package Geometry/Pastemask Top")
		(15 "B.Paste" user "Package Geometry/Pastemask Bottom")
		(5 "F.SilkS" user "Ref Des/Silkscreen Top")
		(7 "B.SilkS" user "Ref Des/Silkscreen Bottom")
		(1 "F.Mask" user "Board Geometry/Soldermask Top")
		(3 "B.Mask" user "Board Geometry/Soldermask Bottom")
		(17 "Dwgs.User" user "User.Drawings")
		(19 "Cmts.User" user "User.Comments")
		(21 "Eco1.User" user "User.Eco1")
		(23 "Eco2.User" user "User.Eco2")
		(25 "Edge.Cuts" user "Board Geometry/Outline")
		(27 "Margin" user)
		(31 "F.CrtYd" user "Package Geometry/Place Bound Top")
		(29 "B.CrtYd" user "Package Geometry/Place Bound Bottom")
		(35 "F.Fab" user "Ref Des/Assembly Top")
		(33 "B.Fab" user "Ref Des/Assembly Bottom")
	)
	(footprint ""
		(layer "F.Cu")
		(at 437.690006 -43.568874 180)
		(property "Reference" "R25W51"
			(at 0 0 180)
			(layer "F.SilkS")
			(hide yes)
			(effects
				(font
					(size 1.27 1.27)
				)
			)
		)
		(property "Value" "*"
			(at 0.064008 -4.108196 180)
			(unlocked yes)
			(layer "F.Fab")
			(hide yes)
			(effects
				(font
					(size 1.27 1.016)
					(thickness 0.1524)
				)
			)
		)
		(property "Device Type" "120R2F-GP_RCL_GP-120R2F-GP,64.A"
			(at 0.064008 -5.632196 180)
			(unlocked yes)
			(layer "F.Fab")
			(hide yes)
			(effects
				(font
					(size 1.27 1.016)
					(thickness 0.1524)
				)
			)
		)
		(duplicate_pad_numbers_are_jumpers no)
		(fp_line
			(start 0.508 -0.9398)
			(end -0.508 -0.9398)
			(stroke
				(width 0.1524)
				(type default)
			)
			(layer "F.SilkS")
		)
		(fp_line
			(start -0.508 -0.9398)
			(end -0.508 0.9398)
			(stroke
				(width 0.1524)
				(type default)
			)
			(layer "F.SilkS")
		)
		(fp_rect
			(start -0.508 0.9398)
			(end 0.508 -0.9398)
			(stroke
				(width 0)
				(type default)
			)
			(fill no)
			(layer "F.CrtYd")
		)
		(fp_rect
			(start -0.508 0.9398)
			(end 0.508 -0.9398)
			(stroke
				(width 0)
				(type default)
			)
			(fill no)
			(layer "F.Fab")
		)
		(pad "1" smd custom
			(at 0 -0.4445 180)
			(size 0.1397 0.1397)
			(layers "F.Cu" "F.Mask" "F.Paste")
			(net "BMC_M_A13")
			(options
				(clearance outline)
				(anchor circle)
			)
			(primitives
				(gr_poly
					(pts
						(arc
							(start -0.1778 -0.2794)
							(mid -0.249642 -0.249642)
							(end -0.2794 -0.1778)
						)
						(arc
							(start -0.2794 0.1778)
							(mid -0.249642 0.249642)
							(end -0.1778 0.2794)
						)
						(arc
							(start 0.1778 0.2794)
							(mid 0.249642 0.249642)
							(end 0.2794 0.1778)
						)
						(arc
							(start 0.2794 -0.1778)
							(mid 0.249642 -0.249642)
							(end 0.1778 -0.2794)
						)
					)
					(width 0)
					(fill yes)
				)
			)
		)
		(pad "2" smd custom
			(at 0 0.4445 180)
			(size 0.1397 0.1397)
			(layers "F.Cu" "F.Mask" "F.Paste")
			(net "P1V2_AUX_BMC")
			(options
				(clearance outline)
				(anchor circle)
			)
			(primitives
				(gr_poly
					(pts
						(arc
							(start -0.1778 -0.2794)
							(mid -0.249642 -0.249642)
							(end -0.2794 -0.1778)
						)
						(arc
							(start -0.2794 0.1778)
							(mid -0.249642 0.249642)
							(end -0.1778 0.2794)
						)
						(arc
							(start 0.1778 0.2794)
							(mid 0.249642 0.249642)
							(end 0.2794 0.1778)
						)
						(arc
							(start 0.2794 -0.1778)
							(mid 0.249642 -0.249642)
							(end 0.1778 -0.2794)
						)
					)
					(width 0)
					(fill yes)
				)
			)
		)
	)
	(footprint ""
		(layer "F.Cu")
		(at 13.1572 -40.005 -90)
		(property "Reference" "R1F8"
			(at 0 0 270)
			(layer "F.SilkS")
			(hide yes)
			(effects
				(font
					(size 1.27 1.27)
				)
			)
		)
		(property "Value" ""
			(at 0 0 270)
			(layer "F.Fab")
			(effects
				(font
					(size 1.27 1.27)
				)
			)
		)
		(duplicate_pad_numbers_are_jumpers no)
		(fp_poly
			(pts
				(xy -0.2794 -0.1016) (xy 0.2794 -0.1016) (xy 0.2794 0.9906) (xy -0.2794 0.9906)
			)
			(stroke
				(width 0)
				(type default)
			)
			(fill no)
			(layer "F.CrtYd")
		)
		(fp_line
			(start -0.2794 0.9906)
			(end 0.2794 0.9906)
			(stroke
				(width 0.1)
				(type default)
			)
			(layer "F.Fab")
		)
		(fp_line
			(start 0.2794 0.9906)
			(end 0.2794 -0.1016)
			(stroke
				(width 0.1)
				(type default)
			)
			(layer "F.Fab")
		)
		(fp_line
			(start -0.2794 -0.1016)
			(end -0.2794 0.9906)
			(stroke
				(width 0.1)
				(type default)
			)
			(layer "F.Fab")
		)
		(fp_line
			(start 0.2794 -0.1016)
			(end -0.2794 -0.1016)
			(stroke
				(width 0.1)
				(type default)
			)
			(layer "F.Fab")
		)
		(pad "1" smd rect
			(at 0 0 270)
			(size 0.508 0.508)
			(layers "F.Cu" "F.Mask" "F.Paste")
			(net "FAN_TACH0")
		)
		(pad "2" smd rect
			(at 0 0.889 270)
			(size 0.508 0.508)
			(layers "F.Cu" "F.Mask" "F.Paste")
			(net "FAN_TACH0_R")
		)
		(zone
			(layer "F.Cu")
			(hatch none 0.5)
			(connect_pads
				(clearance 0)
			)
			(min_thickness 0.25)
			(keepout
				(tracks not_allowed)
				(vias allowed)
				(pads allowed)
				(copperpour not_allowed)
				(footprints allowed)
			)
			(placement
				(enabled no)
				(sheetname "")
			)
			(fill
				(thermal_gap 0.5)
				(thermal_bridge_width 0.5)
				(island_removal_mode 0)
			)
			(polygon
				(pts
					(xy 12.5222 -40.259) (xy 12.5222 -39.751) (xy 12.9032 -39.751) (xy 12.9032 -40.259)
				)
			)
		)
		(zone
			(layer "F.Cu")
			(hatch none 0.5)
			(connect_pads
				(clearance 0)
			)
			(min_thickness 0.25)
			(keepout
				(tracks allowed)
				(vias not_allowed)
				(pads allowed)
				(copperpour not_allowed)
				(footprints allowed)
			)
			(placement
				(enabled no)
				(sheetname "")
			)
			(fill
				(thermal_gap 0.5)
				(thermal_bridge_width 0.5)
				(island_removal_mode 0)
			)
			(polygon
				(pts
					(xy 12.9032 -40.259) (xy 12.9032 -39.751) (xy 12.5222 -39.751) (xy 12.5222 -40.259)
				)
			)
		)
	)
	(footprint ""
		(layer "F.Cu")
		(at 402.382482 -29.382466)
		(property "Reference" "R25W87"
			(at -0.8382 -0.67818 0)
			(unlocked yes)
			(layer "F.SilkS")
			(effects
				(font
					(size 0.4064 0.254)
					(thickness 0.1524)
				)
				(justify left)
			)
		)
		(property "Value" ""
			(at 0 0 0)
			(layer "F.Fab")
			(effects
				(font
					(size 1.27 1.27)
				)
			)
		)
		(duplicate_pad_numbers_are_jumpers no)
		(fp_poly
			(pts
				(xy -0.2794 -0.1016) (xy 0.2794 -0.1016) (xy 0.2794 0.9906) (xy -0.2794 0.9906)
			)
			(stroke
				(width 0)
				(type default)
			)
			(fill no)
			(layer "F.CrtYd")
		)
		(fp_line
			(start -0.2794 -0.1016)
			(end -0.2794 0.9906)
			(stroke
				(width 0.1)
				(type default)
			)
			(layer "F.Fab")
		)
		(fp_line
			(start -0.2794 0.9906)
			(end 0.2794 0.9906)
			(stroke
				(width 0.1)
				(type default)
			)
			(layer "F.Fab")
		)
		(fp_line
			(start 0.2794 -0.1016)
			(end -0.2794 -0.1016)
			(stroke
				(width 0.1)
				(type default)
			)
			(layer "F.Fab")
		)
		(fp_line
			(start 0.2794 0.9906)
			(end 0.2794 -0.1016)
			(stroke
				(width 0.1)
				(type default)
			)
			(layer "F.Fab")
		)
		(pad "1" smd rect
			(at 0 0)
			(size 0.508 0.508)
			(layers "F.Cu" "F.Mask" "F.Paste")
			(net "RMII_BMC_OCP_TXD1_R")
		)
		(pad "2" smd rect
			(at 0 0.889)
			(size 0.508 0.508)
			(layers "F.Cu" "F.Mask" "F.Paste")
			(net "RMII_BMC_OCP_TXD1")
		)
		(zone
			(layer "F.Cu")
			(hatch none 0.5)
			(connect_pads
				(clearance 0)
			)
			(min_thickness 0.25)
			(keepout
				(tracks allowed)
				(vias not_allowed)
				(pads allowed)
				(copperpour not_allowed)
				(footprints allowed)
			)
			(placement
				(enabled no)
				(sheetname "")
			)
			(fill
				(thermal_gap 0.5)
				(thermal_bridge_width 0.5)
				(island_removal_mode 0)
			)
			(polygon
				(pts
					(xy 402.128482 -29.128466) (xy 402.636482 -29.128466) (xy 402.636482 -28.747466) (xy 402.128482 -28.747466)
				)
			)
		)
		(zone
			(layer "F.Cu")
			(hatch none 0.5)
			(connect_pads
				(clearance 0)
			)
			(min_thickness 0.25)
			(keepout
				(tracks not_allowed)
				(vias allowed)
				(pads allowed)
				(copperpour not_allowed)
				(footprints allowed)
			)
			(placement
				(enabled no)
				(sheetname "")
			)
			(fill
				(thermal_gap 0.5)
				(thermal_bridge_width 0.5)
				(island_removal_mode 0)
			)
			(polygon
				(pts
					(xy 402.128482 -28.747466) (xy 402.636482 -28.747466) (xy 402.636482 -29.128466) (xy 402.128482 -29.128466)
				)
			)
		)
	)
	(footprint ""
		(layer "F.Cu")
		(at 396.515082 -157.707076 -90)
		(property "Reference" "RF24"
			(at -0.8382 -0.67818 270)
			(unlocked yes)
			(layer "F.SilkS")
			(effects
				(font
					(size 0.4064 0.254)
					(thickness 0.1524)
				)
				(justify left)
			)
		)
		(property "Value" ""
			(at 0 0 270)
			(layer "F.Fab")
			(effects
				(font
					(size 1.27 1.27)
				)
			)
		)
		(duplicate_pad_numbers_are_jumpers no)
		(fp_poly
			(pts
				(xy -0.2794 -0.1016) (xy 0.2794 -0.1016) (xy 0.2794 0.9906) (xy -0.2794 0.9906)
			)
			(stroke
				(width 0)
				(type default)
			)
			(fill no)
			(layer "F.CrtYd")
		)
		(fp_line
			(start -0.2794 0.9906)
			(end 0.2794 0.9906)
			(stroke
				(width 0.1)
				(type default)
			)
			(layer "F.Fab")
		)
		(fp_line
			(start 0.2794 0.9906)
			(end 0.2794 -0.1016)
			(stroke
				(width 0.1)
				(type default)
			)
			(layer "F.Fab")
		)
		(fp_line
			(start -0.2794 -0.1016)
			(end -0.2794 0.9906)
			(stroke
				(width 0.1)
				(type default)
			)
			(layer "F.Fab")
		)
		(fp_line
			(start 0.2794 -0.1016)
			(end -0.2794 -0.1016)
			(stroke
				(width 0.1)
				(type default)
			)
			(layer "F.Fab")
		)
		(pad "1" smd rect
			(at 0 0 270)
			(size 0.508 0.508)
			(layers "F.Cu" "F.Mask" "F.Paste")
			(net "VR_P1V05_PCH_BIREF1")
		)
		(pad "2" smd rect
			(at 0 0.889 270)
			(size 0.508 0.508)
			(layers "F.Cu" "F.Mask" "F.Paste")
			(net "ISENSE_P1V05_PCH_STBY_PH1_IMON")
		)
		(zone
			(layer "F.Cu")
			(hatch none 0.5)
			(connect_pads
				(clearance 0)
			)
			(min_thickness 0.25)
			(keepout
				(tracks not_allowed)
				(vias allowed)
				(pads allowed)
				(copperpour not_allowed)
				(footprints allowed)
			)
			(placement
				(enabled no)
				(sheetname "")
			)
			(fill
				(thermal_gap 0.5)
				(thermal_bridge_width 0.5)
				(island_removal_mode 0)
			)
			(polygon
				(pts
					(xy 395.880082 -157.961076) (xy 395.880082 -157.453076) (xy 396.261082 -157.453076) (xy 396.261082 -157.961076)
				)
			)
		)
		(zone
			(layer "F.Cu")
			(hatch none 0.5)
			(connect_pads
				(clearance 0)
			)
			(min_thickness 0.25)
			(keepout
				(tracks allowed)
				(vias not_allowed)
				(pads allowed)
				(copperpour not_allowed)
				(footprints allowed)
			)
			(placement
				(enabled no)
				(sheetname "")
			)
			(fill
				(thermal_gap 0.5)
				(thermal_bridge_width 0.5)
				(island_removal_mode 0)
			)
			(polygon
				(pts
					(xy 396.261082 -157.961076) (xy 396.261082 -157.453076) (xy 395.880082 -157.453076) (xy 395.880082 -157.961076)
				)
			)
		)
	)
	(footprint ""
		(layer "F.Cu")
		(at 492.228886 -47.458884)
		(property "Reference" "R25W139"
			(at -0.8382 -0.67818 0)
			(unlocked yes)
			(layer "F.SilkS")
			(effects
				(font
					(size 0.4064 0.254)
					(thickness 0.1524)
				)
				(justify left)
			)
		)
		(property "Value" ""
			(at 0 0 0)
			(layer "F.Fab")
			(effects
				(font
					(size 1.27 1.27)
				)
			)
		)
		(duplicate_pad_numbers_are_jumpers no)
		(fp_poly
			(pts
				(xy -0.2794 -0.1016) (xy 0.2794 -0.1016) (xy 0.2794 0.9906) (xy -0.2794 0.9906)
			)
			(stroke
				(width 0)
				(type default)
			)
			(fill no)
			(layer "F.CrtYd")
		)
		(fp_line
			(start -0.2794 -0.1016)
			(end -0.2794 0.9906)
			(stroke
				(width 0.1)
				(type default)
			)
			(layer "F.Fab")
		)
		(fp_line
			(start -0.2794 0.9906)
			(end 0.2794 0.9906)
			(stroke
				(width 0.1)
				(type default)
			)
			(layer "F.Fab")
		)
		(fp_line
			(start 0.2794 -0.1016)
			(end -0.2794 -0.1016)
			(stroke
				(width 0.1)
				(type default)
			)
			(layer "F.Fab")
		)
		(fp_line
			(start 0.2794 0.9906)
			(end 0.2794 -0.1016)
			(stroke
				(width 0.1)
				(type default)
			)
			(layer "F.Fab")
		)
		(pad "1" smd rect
			(at 0 0)
			(size 0.508 0.508)
			(layers "F.Cu" "F.Mask" "F.Paste")
			(net "VGA_REAR_VSYNC_S")
		)
		(pad "2" smd rect
			(at 0 0.889)
			(size 0.508 0.508)
			(layers "F.Cu" "F.Mask" "F.Paste")
			(net "V_IO_VSYNC_J")
		)
		(zone
			(layer "F.Cu")
			(hatch none 0.5)
			(connect_pads
				(clearance 0)
			)
			(min_thickness 0.25)
			(keepout
				(tracks allowed)
				(vias not_allowed)
				(pads allowed)
				(copperpour not_allowed)
				(footprints allowed)
			)
			(placement
				(enabled no)
				(sheetname "")
			)
			(fill
				(thermal_gap 0.5)
				(thermal_bridge_width 0.5)
				(island_removal_mode 0)
			)
			(polygon
				(pts
					(xy 491.974886 -47.204884) (xy 492.482886 -47.204884) (xy 492.482886 -46.823884) (xy 491.974886 -46.823884)
				)
			)
		)
		(zone
			(layer "F.Cu")
			(hatch none 0.5)
			(connect_pads
				(clearance 0)
			)
			(min_thickness 0.25)
			(keepout
				(tracks not_allowed)
				(vias allowed)
				(pads allowed)
				(copperpour not_allowed)
				(footprints allowed)
			)
			(placement
				(enabled no)
				(sheetname "")
			)
			(fill
				(thermal_gap 0.5)
				(thermal_bridge_width 0.5)
				(island_removal_mode 0)
			)
			(polygon
				(pts
					(xy 491.974886 -46.823884) (xy 492.482886 -46.823884) (xy 492.482886 -47.204884) (xy 491.974886 -47.204884)
				)
			)
		)
	)
	(footprint ""
		(layer "F.Cu")
		(at 368.4016 -130.429 180)
		(property "Reference" "C7B21"
			(at 0 0 180)
			(layer "F.SilkS")
			(hide yes)
			(effects
				(font
					(size 1.27 1.27)
				)
			)
		)
		(property "Value" ""
			(at 0 0 180)
			(layer "F.Fab")
			(effects
				(font
					(size 1.27 1.27)
				)
			)
		)
		(duplicate_pad_numbers_are_jumpers no)
		(fp_poly
			(pts
				(xy -0.4953 -0.2032) (xy 0.4953 -0.2032) (xy 0.4953 1.6002) (xy -0.4953 1.6002)
			)
			(stroke
				(width 0)
				(type default)
			)
			(fill no)
			(layer "F.CrtYd")
		)
		(fp_line
			(start 0.4953 1.6002)
			(end -0.4953 1.6002)
			(stroke
				(width 0.1)
				(type default)
			)
			(layer "F.Fab")
		)
		(fp_line
			(start 0.4953 -0.2032)
			(end 0.4953 1.6002)
			(stroke
				(width 0.1)
				(type default)
			)
			(layer "F.Fab")
		)
		(fp_line
			(start -0.4953 1.6002)
			(end -0.4953 -0.2032)
			(stroke
				(width 0.1)
				(type default)
			)
			(layer "F.Fab")
		)
		(fp_line
			(start -0.4953 -0.2032)
			(end 0.4953 -0.2032)
			(stroke
				(width 0.1)
				(type default)
			)
			(layer "F.Fab")
		)
		(pad "1" smd rect
			(at 0 0 180)
			(size 0.762 0.889)
			(layers "F.Cu" "F.Mask" "F.Paste")
			(net "P1V05_PCH_STBY")
		)
		(pad "2" smd rect
			(at 0 1.397 180)
			(size 0.762 0.889)
			(layers "F.Cu" "F.Mask" "F.Paste")
			(net "GND")
		)
		(zone
			(layer "F.Cu")
			(hatch none 0.5)
			(connect_pads
				(clearance 0)
			)
			(min_thickness 0.25)
			(keepout
				(tracks not_allowed)
				(vias allowed)
				(pads allowed)
				(copperpour not_allowed)
				(footprints allowed)
			)
			(placement
				(enabled no)
				(sheetname "")
			)
			(fill
				(thermal_gap 0.5)
				(thermal_bridge_width 0.5)
				(island_removal_mode 0)
			)
			(polygon
				(pts
					(xy 368.7826 -130.8735) (xy 368.0206 -130.8735) (xy 368.0206 -131.3815) (xy 368.7826 -131.3815)
				)
			)
		)
	)
	(footprint ""
		(layer "F.Cu")
		(at 419.0746 -21.6535)
		(property "Reference" "R2U1"
			(at 0 0 0)
			(layer "F.SilkS")
			(hide yes)
			(effects
				(font
					(size 1.27 1.27)
				)
			)
		)
		(property "Value" ""
			(at 0 0 0)
			(layer "F.Fab")
			(effects
				(font
					(size 1.27 1.27)
				)
			)
		)
		(duplicate_pad_numbers_are_jumpers no)
		(fp_poly
			(pts
				(xy -0.2794 -0.1016) (xy 0.2794 -0.1016) (xy 0.2794 0.9906) (xy -0.2794 0.9906)
			)
			(stroke
				(width 0)
				(type default)
			)
			(fill no)
			(layer "F.CrtYd")
		)
		(fp_line
			(start -0.2794 -0.1016)
			(end -0.2794 0.9906)
			(stroke
				(width 0.1)
				(type default)
			)
			(layer "F.Fab")
		)
		(fp_line
			(start -0.2794 0.9906)
			(end 0.2794 0.9906)
			(stroke
				(width 0.1)
				(type default)
			)
			(layer "F.Fab")
		)
		(fp_line
			(start 0.2794 -0.1016)
			(end -0.2794 -0.1016)
			(stroke
				(width 0.1)
				(type default)
			)
			(layer "F.Fab")
		)
		(fp_line
			(start 0.2794 0.9906)
			(end 0.2794 -0.1016)
			(stroke
				(width 0.1)
				(type default)
			)
			(layer "F.Fab")
		)
		(pad "1" smd rect
			(at 0 0)
			(size 0.508 0.508)
			(layers "F.Cu" "F.Mask" "F.Paste")
			(net "SMB_BMC_PMBUS_STBY_LVC3_SCL_R")
		)
		(pad "2" smd rect
			(at 0 0.889)
			(size 0.508 0.508)
			(layers "F.Cu" "F.Mask" "F.Paste")
			(net "SMB_BMC_PMBUS_STBY_LVC3_SCL")
		)
		(zone
			(layer "F.Cu")
			(hatch none 0.5)
			(connect_pads
				(clearance 0)
			)
			(min_thickness 0.25)
			(keepout
				(tracks allowed)
				(vias not_allowed)
				(pads allowed)
				(copperpour not_allowed)
				(footprints allowed)
			)
			(placement
				(enabled no)
				(sheetname "")
			)
			(fill
				(thermal_gap 0.5)
				(thermal_bridge_width 0.5)
				(island_removal_mode 0)
			)
			(polygon
				(pts
					(xy 418.8206 -21.3995) (xy 419.3286 -21.3995) (xy 419.3286 -21.0185) (xy 418.8206 -21.0185)
				)
			)
		)
		(zone
			(layer "F.Cu")
			(hatch none 0.5)
			(connect_pads
				(clearance 0)
			)
			(min_thickness 0.25)
			(keepout
				(tracks not_allowed)
				(vias allowed)
				(pads allowed)
				(copperpour not_allowed)
				(footprints allowed)
			)
			(placement
				(enabled no)
				(sheetname "")
			)
			(fill
				(thermal_gap 0.5)
				(thermal_bridge_width 0.5)
				(island_removal_mode 0)
			)
			(polygon
				(pts
					(xy 418.8206 -21.0185) (xy 419.3286 -21.0185) (xy 419.3286 -21.3995) (xy 418.8206 -21.3995)
				)
			)
		)
	)
)
